(kicad_pcb
	(version 20241229)
	(generator "pcbnew")
	(generator_version "9.0")
	(general
		(thickness 1.294)
		(legacy_teardrops no)
	)
	(paper "A3")
	(title_block
		(title "Kintex 410T devboard")
		(date "2024-04-03")
		(rev "1.1.2")
		(comment 9 "footprints 397-402 of 975")
	)
	(layers
		(0 "F.Cu" mixed)
		(4 "In1.Cu" power)
		(6 "In2.Cu" power)
		(8 "In3.Cu" mixed)
		(10 "In4.Cu" power)
		(12 "In5.Cu" mixed)
		(14 "In6.Cu" power)
		(16 "In7.Cu" mixed)
		(18 "In8.Cu" power)
		(2 "B.Cu" mixed)
		(9 "F.Adhes" user "F.Adhesive")
		(11 "B.Adhes" user "B.Adhesive")
		(13 "F.Paste" user)
		(15 "B.Paste" user)
		(5 "F.SilkS" user "F.Silkscreen")
		(7 "B.SilkS" user "B.Silkscreen")
		(1 "F.Mask" user)
		(3 "B.Mask" user)
		(17 "Dwgs.User" user "User.Drawings")
		(19 "Cmts.User" user "User.Comments")
		(21 "Eco1.User" user "User.Eco1")
		(23 "Eco2.User" user "User.Eco2")
		(25 "Edge.Cuts" user)
		(27 "Margin" user)
		(31 "F.CrtYd" user "F.Courtyard")
		(29 "B.CrtYd" user "B.Courtyard")
		(35 "F.Fab" user)
		(33 "B.Fab" user)
	)
	(footprint "antmicro-footprints:SC70-3"
		(layer "F.Cu")
		(at 258.4 79)
		(property "Reference" "Q15"
			(at -1.6 1.1 90)
			(layer "F.SilkS")
			(effects
				(font
					(size 0.7 0.7)
					(thickness 0.15)
				)
				(justify left bottom)
			)
		)
		(property "Value" "BSS138PW"
			(at 0 2.3 0)
			(layer "F.Fab")
			(effects
				(font
					(size 0.7 0.7)
					(thickness 0.15)
				)
				(justify left bottom)
			)
		)
		(property "Description" "Power MOSFET, N Channel, 60 V, 320 mA, 0.9 ohm, SOT-323, Surface Mount"
			(at 0 0 0)
			(layer "F.Fab")
			(hide yes)
			(effects
				(font
					(size 1.27 1.27)
					(thickness 0.15)
				)
			)
		)
		(property "Author" "Antmicro"
			(at 0 0 0)
			(layer "F.Fab")
			(hide yes)
			(effects
				(font
					(size 1 1)
					(thickness 0.15)
				)
			)
		)
		(property "License" "Apache-2.0"
			(at 0 0 0)
			(layer "F.Fab")
			(hide yes)
			(effects
				(font
					(size 1 1)
					(thickness 0.15)
				)
			)
		)
		(property "MPN" "BSS138PW"
			(at 0 0 0)
			(layer "F.Fab")
			(hide yes)
			(effects
				(font
					(size 1 1)
					(thickness 0.15)
				)
			)
		)
		(property "Manufacturer" "Nexperia"
			(at 0 0 0)
			(layer "F.Fab")
			(hide yes)
			(effects
				(font
					(size 1 1)
					(thickness 0.15)
				)
			)
		)
		(sheetname "User GPIO + LED + button + DIP switch")
		(sheetfile "user-gpio.kicad_sch")
		(attr smd)
		(fp_line
			(start -0.3 -1)
			(end 0.627 -0.999)
			(stroke
				(width 0.15)
				(type solid)
			)
			(layer "F.SilkS")
		)
		(fp_line
			(start -0.3 1)
			(end 0.627 1.001)
			(stroke
				(width 0.15)
				(type solid)
			)
			(layer "F.SilkS")
		)
		(fp_line
			(start 0.627 -0.6)
			(end 0.627 -0.999)
			(stroke
				(width 0.15)
				(type solid)
			)
			(layer "F.SilkS")
		)
		(fp_line
			(start 0.627 0.6)
			(end 0.627 1.001)
			(stroke
				(width 0.15)
				(type solid)
			)
			(layer "F.SilkS")
		)
		(fp_line
			(start -1.4 1)
			(end -1.4 -1)
			(stroke
				(width 0.05)
				(type solid)
			)
			(layer "F.CrtYd")
		)
		(fp_line
			(start -0.9 -1.3)
			(end -0.9 -1)
			(stroke
				(width 0.05)
				(type solid)
			)
			(layer "F.CrtYd")
		)
		(fp_line
			(start -0.9 -1.3)
			(end 0.9 -1.3)
			(stroke
				(width 0.05)
				(type solid)
			)
			(layer "F.CrtYd")
		)
		(fp_line
			(start -0.9 -1)
			(end -1.4 -1)
			(stroke
				(width 0.05)
				(type solid)
			)
			(layer "F.CrtYd")
		)
		(fp_line
			(start -0.9 1)
			(end -1.4 1)
			(stroke
				(width 0.05)
				(type solid)
			)
			(layer "F.CrtYd")
		)
		(fp_line
			(start -0.9 1.3)
			(end -0.9 1)
			(stroke
				(width 0.05)
				(type solid)
			)
			(layer "F.CrtYd")
		)
		(fp_line
			(start 0.9 -1.3)
			(end 0.9 -0.4)
			(stroke
				(width 0.05)
				(type solid)
			)
			(layer "F.CrtYd")
		)
		(fp_line
			(start 0.9 -0.4)
			(end 1.4 -0.4)
			(stroke
				(width 0.05)
				(type solid)
			)
			(layer "F.CrtYd")
		)
		(fp_line
			(start 0.9 0.4)
			(end 0.9 1.3)
			(stroke
				(width 0.05)
				(type solid)
			)
			(layer "F.CrtYd")
		)
		(fp_line
			(start 0.9 1.3)
			(end -0.9 1.3)
			(stroke
				(width 0.05)
				(type solid)
			)
			(layer "F.CrtYd")
		)
		(fp_line
			(start 1.4 -0.4)
			(end 1.4 0.4)
			(stroke
				(width 0.05)
				(type solid)
			)
			(layer "F.CrtYd")
		)
		(fp_line
			(start 1.4 0.4)
			(end 0.9 0.4)
			(stroke
				(width 0.05)
				(type solid)
			)
			(layer "F.CrtYd")
		)
		(fp_rect
			(start -0.623 -0.999)
			(end 0.627 1.001)
			(stroke
				(width 0.15)
				(type solid)
			)
			(fill no)
			(layer "F.Fab")
		)
		(pad "1" smd rect
			(at -1.051 -0.65 90)
			(size 0.6 0.6)
			(layers "F.Cu" "F.Mask" "F.Paste")
			(net 1305 "/USER_IO.LED_RED")
			(pinfunction "G")
			(pintype "passive")
		)
		(pad "2" smd rect
			(at -1.051 0.65 90)
			(size 0.6 0.6)
			(layers "F.Cu" "F.Mask" "F.Paste")
			(net 1 "GND")
			(pinfunction "S")
			(pintype "passive")
		)
		(pad "3" smd rect
			(at 1.05 0 90)
			(size 0.6 0.6)
			(layers "F.Cu" "F.Mask" "F.Paste")
			(net 770 "Net-(D24-C)")
			(pinfunction "D")
			(pintype "passive")
		)
	)
	(footprint "antmicro-footprints:R_0402_1005Metric"
		(layer "F.Cu")
		(at 156.2 146.65 90)
		(descr "Resistor SMD 0402")
		(tags "resistor SMD 0402")
		(property "Reference" "R328"
			(at 1.05 -0.5 90)
			(layer "F.SilkS")
			(effects
				(font
					(size 0.7 0.7)
					(thickness 0.15)
				)
				(justify left bottom)
			)
		)
		(property "Value" "R_0R_0402"
			(at 0 1.4 90)
			(layer "F.Fab")
			(effects
				(font
					(size 0.7 0.7)
					(thickness 0.15)
				)
				(justify left bottom)
			)
		)
		(property "Description" "SMD Chip Resistor, Jumper, 0 ohm, 100 mW, 0402 [1005 Metric], Thick Film, General Purpose"
			(at 0 0 90)
			(layer "F.Fab")
			(hide yes)
			(effects
				(font
					(size 1.27 1.27)
					(thickness 0.15)
				)
			)
		)
		(property "Author" "Antmicro"
			(at 302.85 -9.55 0)
			(layer "F.Fab")
			(hide yes)
			(effects
				(font
					(size 1 1)
					(thickness 0.15)
				)
			)
		)
		(property "Current" "1A"
			(at 302.85 -9.55 0)
			(layer "F.Fab")
			(hide yes)
			(effects
				(font
					(size 1 1)
					(thickness 0.15)
				)
			)
		)
		(property "License" "Apache-2.0"
			(at 302.85 -9.55 0)
			(layer "F.Fab")
			(hide yes)
			(effects
				(font
					(size 1 1)
					(thickness 0.15)
				)
			)
		)
		(property "MPN" "ERJ2GE0R00X"
			(at 302.85 -9.55 0)
			(layer "F.Fab")
			(hide yes)
			(effects
				(font
					(size 1 1)
					(thickness 0.15)
				)
			)
		)
		(property "Manufacturer" "Panasonic"
			(at 302.85 -9.55 0)
			(layer "F.Fab")
			(hide yes)
			(effects
				(font
					(size 1 1)
					(thickness 0.15)
				)
			)
		)
		(property "Tolerance" ""
			(at 302.85 -9.55 0)
			(layer "F.Fab")
			(hide yes)
			(effects
				(font
					(size 1 1)
					(thickness 0.15)
				)
			)
		)
		(property "Val" "0R"
			(at 302.85 -9.55 0)
			(layer "F.Fab")
			(hide yes)
			(effects
				(font
					(size 1 1)
					(thickness 0.15)
				)
			)
		)
		(sheetname "DC-DC Converters")
		(sheetfile "dc-dc.kicad_sch")
		(attr smd)
		(fp_rect
			(start -0.925 -0.47)
			(end 0.925 0.47)
			(stroke
				(width 0.05)
				(type default)
			)
			(fill no)
			(layer "F.CrtYd")
		)
		(fp_rect
			(start -0.5 -0.25)
			(end 0.5 0.25)
			(stroke
				(width 0.15)
				(type solid)
			)
			(fill no)
			(layer "F.Fab")
		)
		(pad "1" smd roundrect
			(at -0.48 0 90)
			(size 0.59 0.64)
			(layers "F.Cu" "F.Mask" "F.Paste")
			(roundrect_rratio 0.25)
			(net 622 "+1V85_ADC")
			(pintype "passive")
		)
		(pad "2" smd roundrect
			(at 0.48 0 90)
			(size 0.59 0.64)
			(layers "F.Cu" "F.Mask" "F.Paste")
			(roundrect_rratio 0.25)
			(net 747 "/DC-DC Converters/1V85_OUT")
			(pintype "passive")
		)
	)
	(footprint "antmicro-footprints:R_0603_1608Metric"
		(layer "F.Cu")
		(at 153.5 161.5 90)
		(descr "Resistor SMD 0603")
		(tags "resistor SMD 0603")
		(property "Reference" "R285"
			(at -1.45 -0.6 90)
			(layer "F.SilkS")
			(effects
				(font
					(size 0.7 0.7)
					(thickness 0.15)
				)
				(justify left bottom)
			)
		)
		(property "Value" "R_0R_22.4A_0603"
			(at 0 1.6 90)
			(layer "F.Fab")
			(effects
				(font
					(size 0.7 0.7)
					(thickness 0.15)
				)
				(justify left bottom)
			)
		)
		(property "Description" "SMD Chip Resistor"
			(at 0 0 90)
			(layer "F.Fab")
			(hide yes)
			(effects
				(font
					(size 1.27 1.27)
					(thickness 0.15)
				)
			)
		)
		(property "Author" "Antmicro"
			(at 315 8 0)
			(layer "F.Fab")
			(hide yes)
			(effects
				(font
					(size 1 1)
					(thickness 0.15)
				)
			)
		)
		(property "License" "Apache-2.0"
			(at 315 8 0)
			(layer "F.Fab")
			(hide yes)
			(effects
				(font
					(size 1 1)
					(thickness 0.15)
				)
			)
		)
		(property "MPN" "PMR03EZPJ000"
			(at 315 8 0)
			(layer "F.Fab")
			(hide yes)
			(effects
				(font
					(size 1 1)
					(thickness 0.15)
				)
			)
		)
		(property "Manufacturer" "ROHM Semiconductor"
			(at 315 8 0)
			(layer "F.Fab")
			(hide yes)
			(effects
				(font
					(size 1 1)
					(thickness 0.15)
				)
			)
		)
		(property "Max. Curr." "22.4A"
			(at 315 8 0)
			(layer "F.Fab")
			(hide yes)
			(effects
				(font
					(size 1 1)
					(thickness 0.15)
				)
			)
		)
		(property "Tolerance" "template_tolerance"
			(at 315 8 0)
			(layer "F.Fab")
			(hide yes)
			(effects
				(font
					(size 1 1)
					(thickness 0.15)
				)
			)
		)
		(property "Val" "0R"
			(at 315 8 0)
			(layer "F.Fab")
			(hide yes)
			(effects
				(font
					(size 1 1)
					(thickness 0.15)
				)
			)
		)
		(sheetname "DC-DC Converters")
		(sheetfile "dc-dc.kicad_sch")
		(attr smd)
		(fp_line
			(start -0.15 -0.4)
			(end 0.15 -0.4)
			(stroke
				(width 0.15)
				(type solid)
			)
			(layer "F.SilkS")
		)
		(fp_line
			(start -0.15 0.4)
			(end 0.15 0.4)
			(stroke
				(width 0.15)
				(type solid)
			)
			(layer "F.SilkS")
		)
		(fp_rect
			(start -1.25 -0.65)
			(end 1.25 0.65)
			(stroke
				(width 0.05)
				(type solid)
			)
			(fill no)
			(layer "F.CrtYd")
		)
		(fp_rect
			(start -0.8 -0.4)
			(end 0.8 0.4)
			(stroke
				(width 0.15)
				(type solid)
			)
			(fill no)
			(layer "F.Fab")
		)
		(pad "1" smd roundrect
			(at -0.7 0 90)
			(size 0.8 1)
			(layers "F.Cu" "F.Mask" "F.Paste")
			(roundrect_rratio 0.2)
			(net 733 "/DC-DC Converters/MGTAVCC_local")
			(pintype "passive")
		)
		(pad "2" smd roundrect
			(at 0.7 0 90)
			(size 0.8 1)
			(layers "F.Cu" "F.Mask" "F.Paste")
			(roundrect_rratio 0.2)
			(net 6 "+1V0_MGTAVCC")
			(pintype "passive")
		)
	)
	(footprint "antmicro-footprints:C_0402_1005Metric"
		(layer "F.Cu")
		(at 238.35 133.3)
		(descr "Capacitor SMD 0402")
		(tags "capacitor SMD 0402")
		(property "Reference" "C251"
			(at 2.6 -3.125 0)
			(layer "F.SilkS")
			(effects
				(font
					(size 0.7 0.7)
					(thickness 0.15)
				)
				(justify left bottom)
			)
		)
		(property "Value" "C_100n_0402"
			(at 0 1.169 0)
			(layer "F.Fab")
			(effects
				(font
					(size 0.7 0.7)
					(thickness 0.15)
				)
				(justify left bottom)
			)
		)
		(property "Description" "SMD Multilayer Ceramic Capacitor, 0.1 µF, 50 V, 0402 [1005 Metric], ± 10%, X5R, GRM Series"
			(at 0 0 0)
			(layer "F.Fab")
			(hide yes)
			(effects
				(font
					(size 1.27 1.27)
					(thickness 0.15)
				)
			)
		)
		(property "Author" "Antmicro"
			(at 0 0 0)
			(layer "F.Fab")
			(hide yes)
			(effects
				(font
					(size 1 1)
					(thickness 0.15)
				)
			)
		)
		(property "Dielectric" "X5R"
			(at 0 0 0)
			(layer "F.Fab")
			(hide yes)
			(effects
				(font
					(size 1 1)
					(thickness 0.15)
				)
			)
		)
		(property "License" "Apache-2.0"
			(at 0 0 0)
			(layer "F.Fab")
			(hide yes)
			(effects
				(font
					(size 1 1)
					(thickness 0.15)
				)
			)
		)
		(property "MPN" "GRM155R61H104KE14D"
			(at 0 0 0)
			(layer "F.Fab")
			(hide yes)
			(effects
				(font
					(size 1 1)
					(thickness 0.15)
				)
			)
		)
		(property "Manufacturer" "Murata"
			(at 0 0 0)
			(layer "F.Fab")
			(hide yes)
			(effects
				(font
					(size 1 1)
					(thickness 0.15)
				)
			)
		)
		(property "Val" "100n"
			(at 0 0 0)
			(layer "F.Fab")
			(hide yes)
			(effects
				(font
					(size 1 1)
					(thickness 0.15)
				)
			)
		)
		(property "Voltage" "50V"
			(at 0 0 0)
			(layer "F.Fab")
			(hide yes)
			(effects
				(font
					(size 1 1)
					(thickness 0.15)
				)
			)
		)
		(sheetname "USB PHY")
		(sheetfile "usb-phy.kicad_sch")
		(attr smd)
		(fp_rect
			(start -0.925 -0.47)
			(end 0.925 0.47)
			(stroke
				(width 0.05)
				(type default)
			)
			(fill no)
			(layer "F.CrtYd")
		)
		(fp_line
			(start -0.494 -0.25)
			(end 0.504 -0.25)
			(stroke
				(width 0.15)
				(type solid)
			)
			(layer "F.Fab")
		)
		(fp_line
			(start -0.494 0.248)
			(end -0.494 -0.25)
			(stroke
				(width 0.15)
				(type solid)
			)
			(layer "F.Fab")
		)
		(fp_line
			(start 0.504 -0.25)
			(end 0.504 0.248)
			(stroke
				(width 0.15)
				(type solid)
			)
			(layer "F.Fab")
		)
		(fp_line
			(start 0.504 0.248)
			(end -0.494 0.248)
			(stroke
				(width 0.15)
				(type solid)
			)
			(layer "F.Fab")
		)
		(pad "1" smd roundrect
			(at -0.48 0)
			(size 0.59 0.64)
			(layers "F.Cu" "F.Mask" "F.Paste")
			(roundrect_rratio 0.25)
			(net 1 "GND")
			(pintype "passive")
		)
		(pad "2" smd roundrect
			(at 0.48 0)
			(size 0.59 0.64)
			(layers "F.Cu" "F.Mask" "F.Paste")
			(roundrect_rratio 0.25)
			(net 24 "+3V3")
			(pintype "passive")
		)
	)
	(footprint "antmicro-footprints:R_0402_1005Metric"
		(layer "F.Cu")
		(at 211.9 165.4 90)
		(descr "Resistor SMD 0402")
		(tags "resistor SMD 0402")
		(property "Reference" "R80"
			(at -0.4 -5.25 90)
			(layer "F.SilkS")
			(effects
				(font
					(size 0.7 0.7)
					(thickness 0.15)
				)
				(justify left bottom)
			)
		)
		(property "Value" "R_0R_0402"
			(at 0 1.4 90)
			(layer "F.Fab")
			(effects
				(font
					(size 0.7 0.7)
					(thickness 0.15)
				)
				(justify left bottom)
			)
		)
		(property "Description" "SMD Chip Resistor, Jumper, 0 ohm, 100 mW, 0402 [1005 Metric], Thick Film, General Purpose"
			(at 0 0 90)
			(layer "F.Fab")
			(hide yes)
			(effects
				(font
					(size 1.27 1.27)
					(thickness 0.15)
				)
			)
		)
		(property "Author" "Antmicro"
			(at 377.3 -46.5 0)
			(layer "F.Fab")
			(hide yes)
			(effects
				(font
					(size 1 1)
					(thickness 0.15)
				)
			)
		)
		(property "Current" "1A"
			(at 377.3 -46.5 0)
			(layer "F.Fab")
			(hide yes)
			(effects
				(font
					(size 1 1)
					(thickness 0.15)
				)
			)
		)
		(property "License" "Apache-2.0"
			(at 377.3 -46.5 0)
			(layer "F.Fab")
			(hide yes)
			(effects
				(font
					(size 1 1)
					(thickness 0.15)
				)
			)
		)
		(property "MPN" "ERJ2GE0R00X"
			(at 377.3 -46.5 0)
			(layer "F.Fab")
			(hide yes)
			(effects
				(font
					(size 1 1)
					(thickness 0.15)
				)
			)
		)
		(property "Manufacturer" "Panasonic"
			(at 377.3 -46.5 0)
			(layer "F.Fab")
			(hide yes)
			(effects
				(font
					(size 1 1)
					(thickness 0.15)
				)
			)
		)
		(property "Tolerance" ""
			(at 377.3 -46.5 0)
			(layer "F.Fab")
			(hide yes)
			(effects
				(font
					(size 1 1)
					(thickness 0.15)
				)
			)
		)
		(property "Val" "0R"
			(at 377.3 -46.5 0)
			(layer "F.Fab")
			(hide yes)
			(effects
				(font
					(size 1 1)
					(thickness 0.15)
				)
			)
		)
		(sheetname "SPI Flash + SD Card")
		(sheetfile "spi-flash.kicad_sch")
		(attr smd)
		(fp_rect
			(start -0.925 -0.47)
			(end 0.925 0.47)
			(stroke
				(width 0.05)
				(type default)
			)
			(fill no)
			(layer "F.CrtYd")
		)
		(fp_rect
			(start -0.5 -0.25)
			(end 0.5 0.25)
			(stroke
				(width 0.15)
				(type solid)
			)
			(fill no)
			(layer "F.Fab")
		)
		(pad "1" smd roundrect
			(at -0.48 0 90)
			(size 0.59 0.64)
			(layers "F.Cu" "F.Mask" "F.Paste")
			(roundrect_rratio 0.25)
			(net 407 "/FPGA Bank 33 & 34/USR_FLASH_0.~{CS}")
			(pintype "passive")
		)
		(pad "2" smd roundrect
			(at 0.48 0 90)
			(size 0.59 0.64)
			(layers "F.Cu" "F.Mask" "F.Paste")
			(roundrect_rratio 0.25)
			(net 900 "/SPI Flash + SD Card/USR_FLASH_0_~{CS}")
			(pintype "passive")
		)
	)
	(footprint "antmicro-footprints:FB_0805_2012Metric"
		(layer "F.Cu")
		(at 241 179)
		(descr "FERRITE BEAD 0805")
		(tags "FERRITE BEAD 0805")
		(property "Reference" "FB3"
			(at -1 1.9 0)
			(layer "F.SilkS")
			(effects
				(font
					(size 0.7 0.7)
					(thickness 0.15)
				)
				(justify left bottom)
			)
		)
		(property "Value" "FB_220Z_2A_Murata-BLM21PG_0805"
			(at 0 1.8 0)
			(layer "F.Fab")
			(effects
				(font
					(size 0.7 0.7)
					(thickness 0.15)
				)
				(justify left bottom)
			)
		)
		(property "Description" "Ferrite Bead, 0805 [2012 Metric], 220 ohm, 2 A, BLM21, 0.045 ohm, ± 25%, DC power line"
			(at 0 0 0)
			(layer "F.Fab")
			(hide yes)
			(effects
				(font
					(size 1.27 1.27)
					(thickness 0.15)
				)
			)
		)
		(property "Author" "Antmicro"
			(at 0 0 0)
			(layer "F.Fab")
			(hide yes)
			(effects
				(font
					(size 1 1)
					(thickness 0.15)
				)
			)
		)
		(property "Current" ""
			(at 0 0 0)
			(layer "F.Fab")
			(hide yes)
			(effects
				(font
					(size 1 1)
					(thickness 0.15)
				)
			)
		)
		(property "DNP" "DNP"
			(at 0 0 0)
			(layer "F.Fab")
			(hide yes)
			(effects
				(font
					(size 1 1)
					(thickness 0.15)
				)
			)
		)
		(property "License" "Apache-2.0"
			(at 0 0 0)
			(layer "F.Fab")
			(hide yes)
			(effects
				(font
					(size 1 1)
					(thickness 0.15)
				)
			)
		)
		(property "MPN" "BLM21PG221SN1D"
			(at 0 0 0)
			(layer "F.Fab")
			(hide yes)
			(effects
				(font
					(size 1 1)
					(thickness 0.15)
				)
			)
		)
		(property "Manufacturer" "Murata"
			(at 0 0 0)
			(layer "F.Fab")
			(hide yes)
			(effects
				(font
					(size 1 1)
					(thickness 0.15)
				)
			)
		)
		(property "Val" "220Z/2A"
			(at 0 0 0)
			(layer "F.Fab")
			(hide yes)
			(effects
				(font
					(size 1 1)
					(thickness 0.15)
				)
			)
		)
		(property "dnp" ""
			(at 0 0 0)
			(layer "F.Fab")
			(hide yes)
			(effects
				(font
					(size 1 1)
					(thickness 0.15)
				)
			)
		)
		(property "exclude_from_bom" ""
			(at 0 0 0)
			(layer "F.Fab")
			(hide yes)
			(effects
				(font
					(size 1 1)
					(thickness 0.15)
				)
			)
		)
		(sheetname "Power supply")
		(sheetfile "power-supply.kicad_sch")
		(attr smd exclude_from_bom)
		(fp_line
			(start -0.319 0.698)
			(end 0.281 0.698)
			(stroke
				(width 0.15)
				(type solid)
			)
			(layer "F.SilkS")
		)
		(fp_line
			(start -0.299 -0.698)
			(end 0.299 -0.698)
			(stroke
				(width 0.15)
				(type solid)
			)
			(layer "F.SilkS")
		)
		(fp_rect
			(start 1.95 -0.9)
			(end -1.95 0.9)
			(stroke
				(width 0.05)
				(type default)
			)
			(fill no)
			(layer "F.CrtYd")
		)
		(fp_line
			(start -0.948 -0.681)
			(end 0.948 -0.681)
			(stroke
				(width 0.15)
				(type solid)
			)
			(layer "F.Fab")
		)
		(fp_line
			(start -0.948 -0.676)
			(end -0.948 0.676)
			(stroke
				(width 0.15)
				(type solid)
			)
			(layer "F.Fab")
		)
		(fp_line
			(start -0.948 0.681)
			(end 0.948 0.681)
			(stroke
				(width 0.15)
				(type solid)
			)
			(layer "F.Fab")
		)
		(fp_line
			(start 0.948 -0.676)
			(end 0.948 0.676)
			(stroke
				(width 0.15)
				(type solid)
			)
			(layer "F.Fab")
		)
		(pad "1" smd roundrect
			(at -1.1 0)
			(size 1.2 1.3)
			(layers "F.Cu" "F.Mask" "F.Paste")
			(roundrect_rratio 0.25)
			(net 763 "Net-(D6-Pad2)")
			(pintype "passive")
		)
		(pad "2" smd roundrect
			(at 1.1 0)
			(size 1.2 1.3)
			(layers "F.Cu" "F.Mask" "F.Paste")
			(roundrect_rratio 0.25)
			(net 698 "/Power supply/VDD")
			(pintype "passive")
		)
	)
)
